# S9S_MB_2U (Grand Teton) — schematic netlist excerpt (pin names and nets, part order shuffled) for the footprints in the layout excerpt that follows; sources: Cadence DE-HDL packaged netlist, KiCad conversion of 03242023_DA0F0TMBIJ0_F0T_Motherboard_J_brd_V01_OCP.brd

PC2171  Q_CAPP  330UF 2.5V +10/-35% SPCAP  pkg SMLF  page 290 : A = PVCCFA_EHV_FIVRA_CPU1 ; B = GND
PR402  Q_RES  0 5% CHIP  pkg 0402LF  page 267 : A = P5V ; B = PVCCIN_CPU0_PVCC
C329  Q_CAP  47UF 4V 20% X6S  pkg C0805  page 78 : A = PVCCIN_CPU1 ; B = GND

(kicad_pcb
	(version 20260206)
	(generator "pcbnew")
	(generator_version "10.0")
	(general
		(thickness 1.6)
		(legacy_teardrops no)
	)
	(paper "A4")
	(title_block
		(title "03242023_DA0F0TMBIJ0_F0T_Motherboard_J_brd_V01_OCP.brd")
		(comment 1 "Grand Teton / footprints 4623-4625 of 6105")
	)
	(layers
		(0 "F.Cu" signal "TOP")
		(4 "In1.Cu" signal "GND")
		(6 "In2.Cu" signal "IN1")
		(8 "In3.Cu" signal "GND1")
		(10 "In4.Cu" signal "IN2")
		(12 "In5.Cu" signal "GND2")
		(14 "In6.Cu" signal "IN3")
		(16 "In7.Cu" signal "GND3")
		(18 "In8.Cu" signal "VCC")
		(20 "In9.Cu" signal "VCC1")
		(22 "In10.Cu" signal "GND4")
		(24 "In11.Cu" signal "IN4")
		(26 "In12.Cu" signal "GND5")
		(28 "In13.Cu" signal "IN5")
		(30 "In14.Cu" signal "GND6")
		(32 "In15.Cu" signal "IN6")
		(34 "In16.Cu" signal "GND7")
		(2 "B.Cu" signal "BOTTOM")
		(9 "F.Adhes" user "F.Adhesive")
		(11 "B.Adhes" user "B.Adhesive")
		(13 "F.Paste" user "Package Geometry/Pastemask Top")
		(15 "B.Paste" user "Package Geometry/Pastemask Bottom")
		(5 "F.SilkS" user "Ref Des/Silkscreen Top")
		(7 "B.SilkS" user "Ref Des/Silkscreen Bottom")
		(1 "F.Mask" user "Board Geometry/Soldermask Top")
		(3 "B.Mask" user "Board Geometry/Soldermask Bottom")
		(17 "Dwgs.User" user "User.Drawings")
		(19 "Cmts.User" user "User.Comments")
		(21 "Eco1.User" user "User.Eco1")
		(23 "Eco2.User" user "User.Eco2")
		(25 "Edge.Cuts" user "Board Geometry/Outline")
		(27 "Margin" user)
		(31 "F.CrtYd" user "Package Geometry/Place Bound Top")
		(29 "B.CrtYd" user "Package Geometry/Place Bound Bottom")
		(35 "F.Fab" user "Ref Des/Assembly Top")
		(33 "B.Fab" user "Ref Des/Assembly Bottom")
	)
	(footprint ""
		(layer "B.Cu")
		(at 51.289458 -346.579952 -90)
		(property "Reference" "PC2171"
			(at 0 0 90)
			(layer "B.SilkS")
			(hide yes)
			(effects
				(font
					(size 1.27 1.27)
				)
				(justify mirror)
			)
		)
		(property "Value" ""
			(at 0 0 90)
			(layer "B.Fab")
			(effects
				(font
					(size 1.27 1.27)
				)
				(justify mirror)
			)
		)
		(duplicate_pad_numbers_are_jumpers no)
		(fp_line
			(start -4.533392 2.249932)
			(end 4.533392 2.249932)
			(stroke
				(width 0.1524)
				(type default)
			)
			(layer "B.SilkS")
		)
		(fp_line
			(start 4.533392 2.249932)
			(end 4.533392 -2.249932)
			(stroke
				(width 0.1524)
				(type default)
			)
			(layer "B.SilkS")
		)
		(fp_line
			(start -4.533392 -2.249932)
			(end -4.533392 2.249932)
			(stroke
				(width 0.1524)
				(type default)
			)
			(layer "B.SilkS")
		)
		(fp_line
			(start 4.533392 -2.249932)
			(end -4.533392 -2.249932)
			(stroke
				(width 0.1524)
				(type default)
			)
			(layer "B.SilkS")
		)
		(fp_poly
			(pts
				(xy 4.533392 -2.326132) (xy 5.39242 -2.326132) (xy 5.39242 2.326132) (xy 4.533392 2.326132)
			)
			(stroke
				(width 0)
				(type default)
			)
			(fill yes)
			(layer "B.SilkS")
		)
		(fp_line
			(start -3.750056 2.249932)
			(end 3.750056 2.249932)
			(stroke
				(width 0.1)
				(type default)
			)
			(layer "B.Fab")
		)
		(fp_line
			(start 3.750056 2.249932)
			(end 3.750056 -2.249932)
			(stroke
				(width 0.1)
				(type default)
			)
			(layer "B.Fab")
		)
		(fp_line
			(start -3.750056 -2.249932)
			(end -3.750056 2.249932)
			(stroke
				(width 0.1)
				(type default)
			)
			(layer "B.Fab")
		)
		(fp_line
			(start 3.750056 -2.249932)
			(end -3.750056 -2.249932)
			(stroke
				(width 0.1)
				(type default)
			)
			(layer "B.Fab")
		)
		(fp_text user "+"
			(at 6.322314 0.786384 180)
			(unlocked yes)
			(layer "B.SilkS")
			(effects
				(font
					(size 1.905 1.4224)
					(thickness 0.1524)
				)
				(justify left mirror)
			)
		)
		(fp_text user "-"
			(at -4.8514 -0.14605 270)
			(unlocked yes)
			(layer "B.SilkS")
			(effects
				(font
					(size 1.905 1.4224)
					(thickness 0.1524)
				)
				(justify left mirror)
			)
		)
		(fp_text user "+"
			(at 6.322314 0.786384 180)
			(unlocked yes)
			(layer "B.Fab")
			(effects
				(font
					(size 1.905 1.4224)
					(thickness 0.1524)
				)
				(justify left mirror)
			)
		)
		(fp_text user "-"
			(at -4.8514 -0.14605 270)
			(unlocked yes)
			(layer "B.Fab")
			(effects
				(font
					(size 1.905 1.4224)
					(thickness 0.1524)
				)
				(justify left mirror)
			)
		)
		(pad "1" smd rect
			(at 3.199892 0 90)
			(size 2.413 2.8194)
			(layers "B.Cu" "B.Mask" "B.Paste")
			(net "PVCCFA_EHV_FIVRA_CPU1")
		)
		(pad "2" smd rect
			(at -3.199892 0 90)
			(size 2.413 2.8194)
			(layers "B.Cu" "B.Mask" "B.Paste")
			(net "GND")
		)
	)
	(footprint ""
		(layer "B.Cu")
		(at 116.40312 -255.8542 -90)
		(property "Reference" "C329"
			(at 0 0 90)
			(layer "B.SilkS")
			(hide yes)
			(effects
				(font
					(size 1.27 1.27)
				)
				(justify mirror)
			)
		)
		(property "Value" ""
			(at 0 0 90)
			(layer "B.Fab")
			(effects
				(font
					(size 1.27 1.27)
				)
				(justify mirror)
			)
		)
		(duplicate_pad_numbers_are_jumpers no)
		(fp_line
			(start -1.524 0.762)
			(end 1.524 0.762)
			(stroke
				(width 0.1524)
				(type default)
			)
			(layer "B.SilkS")
		)
		(fp_line
			(start 1.524 0.762)
			(end 1.524 -0.762)
			(stroke
				(width 0.1524)
				(type default)
			)
			(layer "B.SilkS")
		)
		(fp_line
			(start -1.524 -0.762)
			(end -1.524 0.762)
			(stroke
				(width 0.1524)
				(type default)
			)
			(layer "B.SilkS")
		)
		(fp_line
			(start 1.524 -0.762)
			(end -1.524 -0.762)
			(stroke
				(width 0.1524)
				(type default)
			)
			(layer "B.SilkS")
		)
		(fp_line
			(start -1.1049 0.724916)
			(end -1.1049 -0.724916)
			(stroke
				(width 0.1)
				(type default)
			)
			(layer "B.Fab")
		)
		(fp_line
			(start 1.1049 0.724916)
			(end -1.1049 0.724916)
			(stroke
				(width 0.1)
				(type default)
			)
			(layer "B.Fab")
		)
		(fp_line
			(start -1.1049 -0.724916)
			(end 1.1049 -0.724916)
			(stroke
				(width 0.1)
				(type default)
			)
			(layer "B.Fab")
		)
		(fp_line
			(start 1.1049 -0.724916)
			(end 1.1049 0.724916)
			(stroke
				(width 0.1)
				(type default)
			)
			(layer "B.Fab")
		)
		(pad "1" smd rect
			(at 0.889 0 270)
			(size 1.016 1.27)
			(layers "B.Cu" "B.Mask" "B.Paste")
			(net "PVCCIN_CPU1")
		)
		(pad "2" smd rect
			(at -0.889 0 270)
			(size 1.016 1.27)
			(layers "B.Cu" "B.Mask" "B.Paste")
			(net "GND")
		)
	)
	(footprint ""
		(layer "B.Cu")
		(at 323.175884 -343.927938 90)
		(property "Reference" "PR402"
			(at 0 0 90)
			(layer "B.SilkS")
			(hide yes)
			(effects
				(font
					(size 1.27 1.27)
				)
				(justify mirror)
			)
		)
		(property "Value" ""
			(at 0 0 90)
			(layer "B.Fab")
			(effects
				(font
					(size 1.27 1.27)
				)
				(justify mirror)
			)
		)
		(duplicate_pad_numbers_are_jumpers no)
		(fp_line
			(start 0.7874 -0.4064)
			(end -0.7874 -0.4064)
			(stroke
				(width 0.1524)
				(type default)
			)
			(layer "B.SilkS")
		)
		(fp_line
			(start -0.7874 -0.4064)
			(end -0.7874 0.4064)
			(stroke
				(width 0.1524)
				(type default)
			)
			(layer "B.SilkS")
		)
		(fp_line
			(start 0.7874 0.4064)
			(end 0.7874 -0.4064)
			(stroke
				(width 0.1524)
				(type default)
			)
			(layer "B.SilkS")
		)
		(fp_line
			(start -0.7874 0.4064)
			(end 0.7874 0.4064)
			(stroke
				(width 0.1524)
				(type default)
			)
			(layer "B.SilkS")
		)
		(fp_line
			(start 0.67945 -0.305054)
			(end 0.12065 -0.305054)
			(stroke
				(width 0.1)
				(type default)
			)
			(layer "B.Fab")
		)
		(fp_line
			(start 0.12065 -0.305054)
			(end 0.12065 -0.2794)
			(stroke
				(width 0.1)
				(type default)
			)
			(layer "B.Fab")
		)
		(fp_line
			(start -0.12065 -0.3048)
			(end -0.67945 -0.3048)
			(stroke
				(width 0.1)
				(type default)
			)
			(layer "B.Fab")
		)
		(fp_line
			(start -0.67945 -0.3048)
			(end -0.67945 0.3048)
			(stroke
				(width 0.1)
				(type default)
			)
			(layer "B.Fab")
		)
		(fp_line
			(start 0.12065 -0.2794)
			(end -0.12065 -0.2794)
			(stroke
				(width 0.1)
				(type default)
			)
			(layer "B.Fab")
		)
		(fp_line
			(start -0.12065 -0.2794)
			(end -0.12065 -0.3048)
			(stroke
				(width 0.1)
				(type default)
			)
			(layer "B.Fab")
		)
		(fp_line
			(start 0.12065 0.2794)
			(end 0.12065 0.3048)
			(stroke
				(width 0.1)
				(type default)
			)
			(layer "B.Fab")
		)
		(fp_line
			(start -0.120396 0.2794)
			(end 0.12065 0.2794)
			(stroke
				(width 0.1)
				(type default)
			)
			(layer "B.Fab")
		)
		(fp_line
			(start 0.67945 0.3048)
			(end 0.67945 -0.305054)
			(stroke
				(width 0.1)
				(type default)
			)
			(layer "B.Fab")
		)
		(fp_line
			(start 0.12065 0.3048)
			(end 0.67945 0.3048)
			(stroke
				(width 0.1)
				(type default)
			)
			(layer "B.Fab")
		)
		(fp_line
			(start -0.120396 0.3048)
			(end -0.120396 0.2794)
			(stroke
				(width 0.1)
				(type default)
			)
			(layer "B.Fab")
		)
		(fp_line
			(start -0.67945 0.3048)
			(end -0.120396 0.3048)
			(stroke
				(width 0.1)
				(type default)
			)
			(layer "B.Fab")
		)
		(pad "1" smd circle
			(at 0.40005 0 270)
			(size 0 0)
			(layers "B.Cu" "B.Mask" "B.Paste")
			(net "P5V")
		)
		(pad "2" smd circle
			(at -0.40005 0 270)
			(size 0 0)
			(layers "B.Cu" "B.Mask" "B.Paste")
			(net "PVCCIN_CPU0_PVCC")
		)
	)
)
